(kicad_pcb
	(version 20260206)
	(generator "pcbnew")
	(generator_version "10.0")
	(general
		(thickness 1.6)
		(legacy_teardrops no)
	)
	(paper "A4")
	(title_block
		(title "Bryce Canyon_F.DPB_16315-1-OCP.brd")
		(comment 1 "Bryce Canyon / footprints 940-943 of 2223")
	)
	(layers
		(0 "F.Cu" signal "TOP")
		(4 "In1.Cu" signal "L2GND")
		(6 "In2.Cu" signal "L3")
		(8 "In3.Cu" signal "L4GND")
		(10 "In4.Cu" signal "L5")
		(12 "In5.Cu" signal "L6VCC")
		(14 "In6.Cu" signal "L7VCC")
		(16 "In7.Cu" signal "L8")
		(18 "In8.Cu" signal "L9GND")
		(20 "In9.Cu" signal "L10")
		(22 "In10.Cu" signal "L11GND")
		(2 "B.Cu" signal "BOTTOM")
		(9 "F.Adhes" user "F.Adhesive")
		(11 "B.Adhes" user "B.Adhesive")
		(13 "F.Paste" user "Package Geometry/Pastemask Top")
		(15 "B.Paste" user "Package Geometry/Pastemask Bottom")
		(5 "F.SilkS" user "Ref Des/Silkscreen Top")
		(7 "B.SilkS" user "Ref Des/Silkscreen Bottom")
		(1 "F.Mask" user "Board Geometry/Soldermask Top")
		(3 "B.Mask" user "Board Geometry/Soldermask Bottom")
		(17 "Dwgs.User" user "User.Drawings")
		(19 "Cmts.User" user "User.Comments")
		(21 "Eco1.User" user "User.Eco1")
		(23 "Eco2.User" user "User.Eco2")
		(25 "Edge.Cuts" user "Board Geometry/Outline")
		(27 "Margin" user)
		(31 "F.CrtYd" user "Package Geometry/Place Bound Top")
		(29 "B.CrtYd" user "Package Geometry/Place Bound Bottom")
		(35 "F.Fab" user "Ref Des/Assembly Top")
		(33 "B.Fab" user "Ref Des/Assembly Bottom")
	)
	(footprint ""
		(layer "F.Cu")
		(at 365.092234 -299.42028 -90)
		(property "Reference" "R294"
			(at 0 0 270)
			(layer "F.SilkS")
			(hide yes)
			(effects
				(font
					(size 1.27 1.27)
				)
			)
		)
		(property "Value" "2R6F-GP"
			(at -0.0508 -4.8514 270)
			(unlocked yes)
			(layer "F.Fab")
			(hide yes)
			(effects
				(font
					(size 1.016 1.016)
					(thickness 0.1524)
				)
			)
		)
		(property "Device Type" "R1206H26"
			(at 0 -6.3754 270)
			(unlocked yes)
			(layer "F.Fab")
			(hide yes)
			(effects
				(font
					(size 1.016 1.016)
					(thickness 0.1524)
				)
			)
		)
		(duplicate_pad_numbers_are_jumpers no)
		(fp_line
			(start -1.016 2.2352)
			(end -1.016 -2.2352)
			(stroke
				(width 0.1524)
				(type default)
			)
			(layer "F.SilkS")
		)
		(fp_line
			(start 1.016 2.2352)
			(end -1.016 2.2352)
			(stroke
				(width 0.1524)
				(type default)
			)
			(layer "F.SilkS")
		)
		(fp_line
			(start -1.016 -2.2352)
			(end 1.016 -2.2352)
			(stroke
				(width 0.1524)
				(type default)
			)
			(layer "F.SilkS")
		)
		(fp_line
			(start 1.016 -2.2352)
			(end 1.016 2.2352)
			(stroke
				(width 0.1524)
				(type default)
			)
			(layer "F.SilkS")
		)
		(fp_rect
			(start -1.0922 2.3114)
			(end 1.0922 -2.3114)
			(stroke
				(width 0)
				(type default)
			)
			(fill no)
			(layer "F.CrtYd")
		)
		(fp_poly
			(pts
				(xy -1.0922 -2.3114) (xy 1.0922 -2.3114) (xy 1.0922 2.3114) (xy -1.0922 2.3114)
			)
			(stroke
				(width 0)
				(type default)
			)
			(fill no)
			(layer "F.Fab")
		)
		(pad "1" smd rect
			(at 0 -1.397 270)
			(size 1.651 1.27)
			(layers "F.Cu" "F.Mask" "F.Paste")
			(net "P12V_HDD7")
		)
		(pad "2" smd rect
			(at 0 1.397 270)
			(size 1.651 1.27)
			(layers "F.Cu" "F.Mask" "F.Paste")
			(net "12V_PRE_7")
		)
	)
	(footprint ""
		(layer "F.Cu")
		(at 458.5589 -65.826894 180)
		(property "Reference" "C483"
			(at 0 0 180)
			(layer "F.SilkS")
			(hide yes)
			(effects
				(font
					(size 1.27 1.27)
				)
			)
		)
		(property "Value" "SC10U16V6KX-2GP"
			(at -0.0762 -5.1308 180)
			(unlocked yes)
			(layer "F.Fab")
			(hide yes)
			(effects
				(font
					(size 1.016 1.016)
					(thickness 0.1524)
				)
			)
		)
		(property "Device Type" "C1206H71"
			(at -0.127 -6.6548 180)
			(unlocked yes)
			(layer "F.Fab")
			(hide yes)
			(effects
				(font
					(size 1.016 1.016)
					(thickness 0.1524)
				)
			)
		)
		(duplicate_pad_numbers_are_jumpers no)
		(fp_line
			(start 1.016 2.2352)
			(end -1.016 2.2352)
			(stroke
				(width 0.1524)
				(type default)
			)
			(layer "F.SilkS")
		)
		(fp_line
			(start 1.016 0.8382)
			(end 1.016 2.2352)
			(stroke
				(width 0.1524)
				(type default)
			)
			(layer "F.SilkS")
		)
		(fp_line
			(start 1.016 -2.2352)
			(end 1.016 -0.8382)
			(stroke
				(width 0.1524)
				(type default)
			)
			(layer "F.SilkS")
		)
		(fp_line
			(start -1.016 2.2352)
			(end -1.016 0.8382)
			(stroke
				(width 0.1524)
				(type default)
			)
			(layer "F.SilkS")
		)
		(fp_line
			(start -1.016 -0.8382)
			(end -1.016 -2.2352)
			(stroke
				(width 0.1524)
				(type default)
			)
			(layer "F.SilkS")
		)
		(fp_line
			(start -1.016 -2.2352)
			(end 1.016 -2.2352)
			(stroke
				(width 0.1524)
				(type default)
			)
			(layer "F.SilkS")
		)
		(fp_rect
			(start -1.0922 2.3114)
			(end 1.0922 -2.3114)
			(stroke
				(width 0)
				(type default)
			)
			(fill no)
			(layer "F.CrtYd")
		)
		(fp_poly
			(pts
				(xy 1.0922 -2.3114) (xy 1.0922 2.3114) (xy -1.0922 2.3114) (xy -1.0922 -2.3114)
			)
			(stroke
				(width 0)
				(type default)
			)
			(fill no)
			(layer "F.Fab")
		)
		(pad "1" smd rect
			(at 0 -1.397 180)
			(size 1.651 1.27)
			(layers "F.Cu" "F.Mask" "F.Paste")
			(net "P5V_HDD34")
		)
		(pad "2" smd rect
			(at 0 1.397 180)
			(size 1.651 1.27)
			(layers "F.Cu" "F.Mask" "F.Paste")
			(net "GND")
		)
	)
	(footprint ""
		(layer "F.Cu")
		(at 7.440422 -175.988726 90)
		(property "Reference" "R146"
			(at 0 0 90)
			(layer "F.SilkS")
			(hide yes)
			(effects
				(font
					(size 1.27 1.27)
				)
			)
		)
		(property "Value" "4K7R2J-2-GP"
			(at 0.064008 -3.993896 90)
			(unlocked yes)
			(layer "F.Fab")
			(hide yes)
			(effects
				(font
					(size 1.016 1.016)
					(thickness 0.1524)
				)
			)
		)
		(property "Device Type" "R402H16"
			(at 0.064008 -5.517896 90)
			(unlocked yes)
			(layer "F.Fab")
			(hide yes)
			(effects
				(font
					(size 1.016 1.016)
					(thickness 0.1524)
				)
			)
		)
		(duplicate_pad_numbers_are_jumpers no)
		(fp_line
			(start 0.508 -0.9398)
			(end -0.508 -0.9398)
			(stroke
				(width 0.1524)
				(type default)
			)
			(layer "F.SilkS")
		)
		(fp_line
			(start -0.508 -0.9398)
			(end -0.508 0.9398)
			(stroke
				(width 0.1524)
				(type default)
			)
			(layer "F.SilkS")
		)
		(fp_rect
			(start -0.508 0.9398)
			(end 0.508 -0.9398)
			(stroke
				(width 0)
				(type default)
			)
			(fill no)
			(layer "F.CrtYd")
		)
		(fp_rect
			(start -0.508 0.9398)
			(end 0.508 -0.9398)
			(stroke
				(width 0)
				(type default)
			)
			(fill no)
			(layer "F.Fab")
		)
		(pad "1" smd custom
			(at 0 -0.4445 90)
			(size 0.1397 0.1397)
			(layers "F.Cu" "F.Mask" "F.Paste")
			(net "DRIVE_A_0_FLT_LED")
			(options
				(clearance outline)
				(anchor circle)
			)
			(primitives
				(gr_poly
					(pts
						(arc
							(start -0.1778 -0.2794)
							(mid -0.249642 -0.249642)
							(end -0.2794 -0.1778)
						)
						(arc
							(start -0.2794 0.1778)
							(mid -0.249642 0.249642)
							(end -0.1778 0.2794)
						)
						(arc
							(start 0.1778 0.2794)
							(mid 0.249642 0.249642)
							(end 0.2794 0.1778)
						)
						(arc
							(start 0.2794 -0.1778)
							(mid 0.249642 -0.249642)
							(end 0.1778 -0.2794)
						)
					)
					(width 0)
					(fill yes)
				)
			)
		)
		(pad "2" smd custom
			(at 0 0.4445 90)
			(size 0.1397 0.1397)
			(layers "F.Cu" "F.Mask" "F.Paste")
			(net "GND")
			(options
				(clearance outline)
				(anchor circle)
			)
			(primitives
				(gr_poly
					(pts
						(arc
							(start -0.1778 -0.2794)
							(mid -0.249642 -0.249642)
							(end -0.2794 -0.1778)
						)
						(arc
							(start -0.2794 0.1778)
							(mid -0.249642 0.249642)
							(end -0.1778 0.2794)
						)
						(arc
							(start 0.1778 0.2794)
							(mid 0.249642 0.249642)
							(end 0.2794 0.1778)
						)
						(arc
							(start 0.2794 -0.1778)
							(mid 0.249642 -0.249642)
							(end 0.1778 -0.2794)
						)
					)
					(width 0)
					(fill yes)
				)
			)
		)
	)
	(footprint ""
		(layer "F.Cu")
		(at 69.65061 -303.904396)
		(property "Reference" "Q253"
			(at 0 0 0)
			(layer "F.SilkS")
			(hide yes)
			(effects
				(font
					(size 1.27 1.27)
				)
			)
		)
		(property "Value" "2N7002K-2-GP"
			(at 0.127 -8.9662 0)
			(unlocked yes)
			(layer "F.Fab")
			(hide yes)
			(effects
				(font
					(size 1.016 1.016)
					(thickness 0.1524)
				)
			)
		)
		(property "Device Type" "SOT23DGS2D4H44"
			(at 0.127 -10.4902 0)
			(unlocked yes)
			(layer "F.Fab")
			(hide yes)
			(effects
				(font
					(size 1.016 1.016)
					(thickness 0.1524)
				)
			)
		)
		(duplicate_pad_numbers_are_jumpers no)
		(fp_line
			(start -1.651 -1.778)
			(end -1.651 1.778)
			(stroke
				(width 0.1524)
				(type default)
			)
			(layer "F.SilkS")
		)
		(fp_line
			(start -1.651 1.778)
			(end 1.651 1.778)
			(stroke
				(width 0.1524)
				(type default)
			)
			(layer "F.SilkS")
		)
		(fp_line
			(start 1.651 -1.778)
			(end -1.651 -1.778)
			(stroke
				(width 0.1524)
				(type default)
			)
			(layer "F.SilkS")
		)
		(fp_line
			(start 1.651 1.778)
			(end 1.651 -1.778)
			(stroke
				(width 0.1524)
				(type default)
			)
			(layer "F.SilkS")
		)
		(fp_poly
			(pts
				(xy -1.778 1.8796) (xy -1.778 -1.8796) (xy 1.778 -1.8796) (xy 1.778 1.8796)
			)
			(stroke
				(width 0)
				(type default)
			)
			(fill no)
			(layer "F.CrtYd")
		)
		(fp_poly
			(pts
				(xy -1.778 1.8796) (xy -1.778 -1.8796) (xy 1.778 -1.8796) (xy 1.778 1.8796)
			)
			(stroke
				(width 0)
				(type default)
			)
			(fill no)
			(layer "F.Fab")
		)
		(pad "D" smd custom
			(at 0 -0.9525)
			(size 0.1905 0.1905)
			(layers "F.Cu" "F.Mask" "F.Paste")
			(net "FLT_HDD26_N")
			(options
				(clearance outline)
				(anchor circle)
			)
			(primitives
				(gr_poly
					(pts
						(arc
							(start -0.1778 0.5715)
							(mid -0.321484 0.511984)
							(end -0.381 0.3683)
						)
						(arc
							(start -0.381 -0.3683)
							(mid -0.321484 -0.511984)
							(end -0.1778 -0.5715)
						)
						(arc
							(start 0.1778 -0.5715)
							(mid 0.321484 -0.511984)
							(end 0.381 -0.3683)
						)
						(arc
							(start 0.381 0.3683)
							(mid 0.321484 0.511984)
							(end 0.1778 0.5715)
						)
					)
					(width 0)
					(fill yes)
				)
			)
		)
		(pad "G" smd custom
			(at -0.98425 0.9525)
			(size 0.1905 0.1905)
			(layers "F.Cu" "F.Mask" "F.Paste")
			(net "DRIVE_B_26_FLT_LED")
			(options
				(clearance outline)
				(anchor circle)
			)
			(primitives
				(gr_poly
					(pts
						(arc
							(start -0.1778 0.5715)
							(mid -0.321484 0.511984)
							(end -0.381 0.3683)
						)
						(arc
							(start -0.381 -0.3683)
							(mid -0.321484 -0.511984)
							(end -0.1778 -0.5715)
						)
						(arc
							(start 0.1778 -0.5715)
							(mid 0.321484 -0.511984)
							(end 0.381 -0.3683)
						)
						(arc
							(start 0.381 0.3683)
							(mid 0.321484 0.511984)
							(end 0.1778 0.5715)
						)
					)
					(width 0)
					(fill yes)
				)
			)
		)
		(pad "S" smd custom
			(at 0.98425 0.9525)
			(size 0.1905 0.1905)
			(layers "F.Cu" "F.Mask" "F.Paste")
			(net "GND")
			(options
				(clearance outline)
				(anchor circle)
			)
			(primitives
				(gr_poly
					(pts
						(arc
							(start -0.1778 0.5715)
							(mid -0.321484 0.511984)
							(end -0.381 0.3683)
						)
						(arc
							(start -0.381 -0.3683)
							(mid -0.321484 -0.511984)
							(end -0.1778 -0.5715)
						)
						(arc
							(start 0.1778 -0.5715)
							(mid 0.321484 -0.511984)
							(end 0.381 -0.3683)
						)
						(arc
							(start 0.381 0.3683)
							(mid 0.321484 0.511984)
							(end 0.1778 0.5715)
						)
					)
					(width 0)
					(fill yes)
				)
			)
		)
	)
)
